(kicad_pcb
	(version 20211014)
	(generator pcbnew)
	(general
    (thickness 1.6)
  )
	(paper "A4")
	(title_block
    (title "SA800U (Snapdragon 845) Baseboard")
    (date "2023-10-19")
    (rev "1.0.3")
    (company "Antmicro Ltd.")
    (comment 1 "www.antmicro.com")
		(comment 9 "footprints 137-143 of 589")
	)
	(layers
    (0 "F.Cu" signal)
    (1 "In1.Cu" power)
    (2 "In2.Cu" signal)
    (3 "In3.Cu" signal)
    (4 "In4.Cu" power)
    (31 "B.Cu" signal)
    (32 "B.Adhes" user "B.Adhesive")
    (33 "F.Adhes" user "F.Adhesive")
    (34 "B.Paste" user)
    (35 "F.Paste" user)
    (36 "B.SilkS" user "B.Silkscreen")
    (37 "F.SilkS" user "F.Silkscreen")
    (38 "B.Mask" user)
    (39 "F.Mask" user)
    (40 "Dwgs.User" user "User.Drawings")
    (41 "Cmts.User" user "User.Comments")
    (42 "Eco1.User" user "User.Eco1")
    (43 "Eco2.User" user "User.Eco2")
    (44 "Edge.Cuts" user)
    (45 "Margin" user)
    (46 "B.CrtYd" user "B.Courtyard")
    (47 "F.CrtYd" user "F.Courtyard")
    (48 "B.Fab" user)
    (49 "F.Fab" user)
  )
	(footprint "sa800u-baseboard-hw-footprints:R_0402_1005Metric" (layer "F.Cu")
    (tedit 5FD9C158)
    (at 78.45 124.4 90)
    (descr "Resistor SMD 0402")
    (tags "resistor SMD 0402")
    (property "Author" "Antmicro")
    (property "License" "Apache-2.0")
    (property "MPN" "CR0402-FX-3902GLF")
    (property "Manufacturer" "Bourns")
    (property "Sheetfile" "psu.kicad_sch")
    (property "Sheetname" "PSU")
    (property "Tolerance" "1%")
    (property "Val" "39k")
    (attr smd)
    (fp_text reference "R109" (at -8.35 0.17 90) (layer "F.SilkS")
      (effects (font (size 0.7 0.7) (thickness 0.15)) (justify left bottom))
    )
    (fp_text value "R_39k_0402" (at 0 1.4 90) (layer "F.Fab")
      (effects (font (size 0.7 0.7) (thickness 0.15)) (justify left bottom))
    )
    (fp_text user "${REFERENCE}" (at -0.95 3.168 90) (layer "F.Fab") hide
      (effects (font (size 0.7 0.7) (thickness 0.15)) (justify left bottom))
    )
    (fp_text user "Author: Antmicro" (at -0.95 4.169 90) (layer "F.Fab") hide
      (effects (font (size 0.7 0.7) (thickness 0.15)) (justify left bottom))
    )
    (fp_text user "License: Apache-2.0" (at -0.95 5.169 90) (layer "F.Fab") hide
      (effects (font (size 0.7 0.7) (thickness 0.15)) (justify left bottom))
    )
    (fp_rect (start -0.93 -0.47) (end 0.93 0.47) (layer "F.CrtYd") (width 0.05) (fill none))
    (fp_rect (start -0.5 -0.25) (end 0.5 0.25) (layer "F.Fab") (width 0.15) (fill none))
    (pad "1" smd roundrect (at -0.485 0 90) (size 0.59 0.64) (layers "F.Cu" "F.Paste" "F.Mask") (roundrect_rratio 0.25)
      (net 401 "Net-(R108-Pad2)") (pintype "passive"))
    (pad "2" smd roundrect (at 0.485 0 90) (size 0.59 0.64) (layers "F.Cu" "F.Paste" "F.Mask") (roundrect_rratio 0.25)
      (net 128 "Net-(R109-Pad2)") (pintype "passive"))
  )
	(footprint "sa800u-baseboard-hw-footprints:R_0402_1005Metric" (layer "F.Cu")
    (tedit 5FD9C158)
    (at 79.9 124.9 180)
    (descr "Resistor SMD 0402")
    (tags "resistor SMD 0402")
    (property "Author" "Antmicro")
    (property "License" "Apache-2.0")
    (property "MPN" "CR0402-FX-2003GLF")
    (property "Manufacturer" "Bourns")
    (property "Sheetfile" "psu.kicad_sch")
    (property "Sheetname" "PSU")
    (property "Tolerance" "1%")
    (property "Val" "200k")
    (attr smd)
    (fp_text reference "R108" (at 1.24 -6.23 180) (layer "F.SilkS")
      (effects (font (size 0.7 0.7) (thickness 0.15)) (justify left bottom))
    )
    (fp_text value "R_200k_0402" (at 0 1.4 180) (layer "F.Fab")
      (effects (font (size 0.7 0.7) (thickness 0.15)) (justify left bottom))
    )
    (fp_text user "Author: Antmicro" (at -0.95 4.169 180) (layer "F.Fab") hide
      (effects (font (size 0.7 0.7) (thickness 0.15)) (justify left bottom))
    )
    (fp_text user "${REFERENCE}" (at -0.95 3.168 180) (layer "F.Fab") hide
      (effects (font (size 0.7 0.7) (thickness 0.15)) (justify left bottom))
    )
    (fp_text user "License: Apache-2.0" (at -0.95 5.169 180) (layer "F.Fab") hide
      (effects (font (size 0.7 0.7) (thickness 0.15)) (justify left bottom))
    )
    (fp_rect (start -0.93 -0.47) (end 0.93 0.47) (layer "F.CrtYd") (width 0.05) (fill none))
    (fp_rect (start -0.5 -0.25) (end 0.5 0.25) (layer "F.Fab") (width 0.15) (fill none))
    (pad "1" smd roundrect (at -0.485 0 180) (size 0.59 0.64) (layers "F.Cu" "F.Paste" "F.Mask") (roundrect_rratio 0.25)
      (net 142 "PD_VDD") (pintype "passive"))
    (pad "2" smd roundrect (at 0.485 0 180) (size 0.59 0.64) (layers "F.Cu" "F.Paste" "F.Mask") (roundrect_rratio 0.25)
      (net 401 "Net-(R108-Pad2)") (pintype "passive"))
  )
	(footprint "sa800u-baseboard-hw-footprints:R_0402_1005Metric" (layer "F.Cu")
    (tedit 5FD9C158)
    (at 78.45 126.4 90)
    (descr "Resistor SMD 0402")
    (tags "resistor SMD 0402")
    (property "Author" "Antmicro")
    (property "License" "Apache-2.0")
    (property "MPN" "CR0402-FX-3902GLF")
    (property "Manufacturer" "Bourns")
    (property "Sheetfile" "psu.kicad_sch")
    (property "Sheetname" "PSU")
    (property "Tolerance" "1%")
    (property "Val" "39k")
    (attr smd)
    (fp_text reference "R113" (at -9.02 0.19 90) (layer "F.SilkS")
      (effects (font (size 0.7 0.7) (thickness 0.15)) (justify left bottom))
    )
    (fp_text value "R_39k_0402" (at 0 1.4 90) (layer "F.Fab")
      (effects (font (size 0.7 0.7) (thickness 0.15)) (justify left bottom))
    )
    (fp_text user "${REFERENCE}" (at -0.95 3.168 90) (layer "F.Fab") hide
      (effects (font (size 0.7 0.7) (thickness 0.15)) (justify left bottom))
    )
    (fp_text user "Author: Antmicro" (at -0.95 4.169 90) (layer "F.Fab") hide
      (effects (font (size 0.7 0.7) (thickness 0.15)) (justify left bottom))
    )
    (fp_text user "License: Apache-2.0" (at -0.95 5.169 90) (layer "F.Fab") hide
      (effects (font (size 0.7 0.7) (thickness 0.15)) (justify left bottom))
    )
    (fp_rect (start -0.93 -0.47) (end 0.93 0.47) (layer "F.CrtYd") (width 0.05) (fill none))
    (fp_rect (start -0.5 -0.25) (end 0.5 0.25) (layer "F.Fab") (width 0.15) (fill none))
    (pad "1" smd roundrect (at -0.485 0 90) (size 0.59 0.64) (layers "F.Cu" "F.Paste" "F.Mask") (roundrect_rratio 0.25)
      (net 402 "Net-(R112-Pad2)") (pintype "passive"))
    (pad "2" smd roundrect (at 0.485 0 90) (size 0.59 0.64) (layers "F.Cu" "F.Paste" "F.Mask") (roundrect_rratio 0.25)
      (net 403 "Net-(R113-Pad2)") (pintype "passive"))
  )
	(footprint "sa800u-baseboard-hw-footprints:R_0402_1005Metric" (layer "F.Cu")
    (tedit 5FD9C158)
    (at 79.9 122.9 180)
    (descr "Resistor SMD 0402")
    (tags "resistor SMD 0402")
    (property "Author" "Antmicro")
    (property "License" "Apache-2.0")
    (property "MPN" "CR0402-FX-2003GLF")
    (property "Manufacturer" "Bourns")
    (property "Sheetfile" "psu.kicad_sch")
    (property "Sheetname" "PSU")
    (property "Tolerance" "1%")
    (property "Val" "200k")
    (attr smd)
    (fp_text reference "R105" (at 1.21 -6.31 180) (layer "F.SilkS")
      (effects (font (size 0.7 0.7) (thickness 0.15)) (justify left bottom))
    )
    (fp_text value "R_200k_0402" (at 0 1.4 180) (layer "F.Fab")
      (effects (font (size 0.7 0.7) (thickness 0.15)) (justify left bottom))
    )
    (fp_text user "${REFERENCE}" (at -0.95 3.168 180) (layer "F.Fab") hide
      (effects (font (size 0.7 0.7) (thickness 0.15)) (justify left bottom))
    )
    (fp_text user "Author: Antmicro" (at -0.95 4.169 180) (layer "F.Fab") hide
      (effects (font (size 0.7 0.7) (thickness 0.15)) (justify left bottom))
    )
    (fp_text user "License: Apache-2.0" (at -0.95 5.169 180) (layer "F.Fab") hide
      (effects (font (size 0.7 0.7) (thickness 0.15)) (justify left bottom))
    )
    (fp_rect (start -0.93 -0.47) (end 0.93 0.47) (layer "F.CrtYd") (width 0.05) (fill none))
    (fp_rect (start -0.5 -0.25) (end 0.5 0.25) (layer "F.Fab") (width 0.15) (fill none))
    (pad "1" smd roundrect (at -0.485 0 180) (size 0.59 0.64) (layers "F.Cu" "F.Paste" "F.Mask") (roundrect_rratio 0.25)
      (net 136 "5V_POE") (pintype "passive"))
    (pad "2" smd roundrect (at 0.485 0 180) (size 0.59 0.64) (layers "F.Cu" "F.Paste" "F.Mask") (roundrect_rratio 0.25)
      (net 399 "Net-(R105-Pad2)") (pintype "passive"))
  )
	(footprint "sa800u-baseboard-hw-footprints:R_0402_1005Metric" (layer "F.Cu")
    (tedit 5FD9C158)
    (at 79.9 126.9 180)
    (descr "Resistor SMD 0402")
    (tags "resistor SMD 0402")
    (property "Author" "Antmicro")
    (property "License" "Apache-2.0")
    (property "MPN" "CR0402-FX-2003GLF")
    (property "Manufacturer" "Bourns")
    (property "Sheetfile" "psu.kicad_sch")
    (property "Sheetname" "PSU")
    (property "Tolerance" "1%")
    (property "Val" "200k")
    (attr smd)
    (fp_text reference "R112" (at 1.25 -6.22 180) (layer "F.SilkS")
      (effects (font (size 0.7 0.7) (thickness 0.15)) (justify left bottom))
    )
    (fp_text value "R_200k_0402" (at 0 1.4 180) (layer "F.Fab")
      (effects (font (size 0.7 0.7) (thickness 0.15)) (justify left bottom))
    )
    (fp_text user "${REFERENCE}" (at -0.95 3.168 180) (layer "F.Fab") hide
      (effects (font (size 0.7 0.7) (thickness 0.15)) (justify left bottom))
    )
    (fp_text user "License: Apache-2.0" (at -0.95 5.169 180) (layer "F.Fab") hide
      (effects (font (size 0.7 0.7) (thickness 0.15)) (justify left bottom))
    )
    (fp_text user "Author: Antmicro" (at -0.95 4.169 180) (layer "F.Fab") hide
      (effects (font (size 0.7 0.7) (thickness 0.15)) (justify left bottom))
    )
    (fp_rect (start -0.93 -0.47) (end 0.93 0.47) (layer "F.CrtYd") (width 0.05) (fill none))
    (fp_rect (start -0.5 -0.25) (end 0.5 0.25) (layer "F.Fab") (width 0.15) (fill none))
    (pad "1" smd roundrect (at -0.485 0 180) (size 0.59 0.64) (layers "F.Cu" "F.Paste" "F.Mask") (roundrect_rratio 0.25)
      (net 152 "/PSU/AUX_VDD") (pintype "passive"))
    (pad "2" smd roundrect (at 0.485 0 180) (size 0.59 0.64) (layers "F.Cu" "F.Paste" "F.Mask") (roundrect_rratio 0.25)
      (net 402 "Net-(R112-Pad2)") (pintype "passive"))
  )
	(footprint "sa800u-baseboard-hw-footprints:R_0402_1005Metric" (layer "F.Cu")
    (tedit 5FD9C158)
    (at 78.45 122.4 90)
    (descr "Resistor SMD 0402")
    (tags "resistor SMD 0402")
    (property "Author" "Antmicro")
    (property "License" "Apache-2.0")
    (property "MPN" "CR0402-FX-3902GLF")
    (property "Manufacturer" "Bourns")
    (property "Sheetfile" "psu.kicad_sch")
    (property "Sheetname" "PSU")
    (property "Tolerance" "1%")
    (property "Val" "39k")
    (attr smd)
    (fp_text reference "R106" (at -7.66 0.21 90) (layer "F.SilkS")
      (effects (font (size 0.7 0.7) (thickness 0.15)) (justify left bottom))
    )
    (fp_text value "R_39k_0402" (at 0 1.4 90) (layer "F.Fab")
      (effects (font (size 0.7 0.7) (thickness 0.15)) (justify left bottom))
    )
    (fp_text user "${REFERENCE}" (at -0.95 3.168 90) (layer "F.Fab") hide
      (effects (font (size 0.7 0.7) (thickness 0.15)) (justify left bottom))
    )
    (fp_text user "License: Apache-2.0" (at -0.95 5.169 90) (layer "F.Fab") hide
      (effects (font (size 0.7 0.7) (thickness 0.15)) (justify left bottom))
    )
    (fp_text user "Author: Antmicro" (at -0.95 4.169 90) (layer "F.Fab") hide
      (effects (font (size 0.7 0.7) (thickness 0.15)) (justify left bottom))
    )
    (fp_rect (start -0.93 -0.47) (end 0.93 0.47) (layer "F.CrtYd") (width 0.05) (fill none))
    (fp_rect (start -0.5 -0.25) (end 0.5 0.25) (layer "F.Fab") (width 0.15) (fill none))
    (pad "1" smd roundrect (at -0.485 0 90) (size 0.59 0.64) (layers "F.Cu" "F.Paste" "F.Mask") (roundrect_rratio 0.25)
      (net 399 "Net-(R105-Pad2)") (pintype "passive"))
    (pad "2" smd roundrect (at 0.485 0 90) (size 0.59 0.64) (layers "F.Cu" "F.Paste" "F.Mask") (roundrect_rratio 0.25)
      (net 400 "Net-(R106-Pad2)") (pintype "passive"))
  )
	(footprint "sa800u-baseboard-hw-footprints:R_0402_1005Metric" (layer "F.Cu")
    (tedit 5FD9C158)
    (at 76.95 127.55)
    (descr "Resistor SMD 0402")
    (tags "resistor SMD 0402")
    (property "Author" "Antmicro")
    (property "License" "Apache-2.0")
    (property "MPN" "CR0402-FX-2553GLF")
    (property "Manufacturer" "Bourns")
    (property "Sheetfile" "psu.kicad_sch")
    (property "Sheetname" "PSU")
    (property "Tolerance" "1%")
    (property "Val" "255k")
    (attr smd)
    (fp_text reference "R117" (at -3.68 0.38) (layer "F.SilkS")
      (effects (font (size 0.7 0.7) (thickness 0.15)) (justify left bottom))
    )
    (fp_text value "R_255k_0402" (at 0 1.4) (layer "F.Fab")
      (effects (font (size 0.7 0.7) (thickness 0.15)) (justify left bottom))
    )
    (fp_text user "Author: Antmicro" (at -0.95 4.169) (layer "F.Fab") hide
      (effects (font (size 0.7 0.7) (thickness 0.15)) (justify left bottom))
    )
    (fp_text user "${REFERENCE}" (at -0.95 3.168) (layer "F.Fab") hide
      (effects (font (size 0.7 0.7) (thickness 0.15)) (justify left bottom))
    )
    (fp_text user "License: Apache-2.0" (at -0.95 5.169) (layer "F.Fab") hide
      (effects (font (size 0.7 0.7) (thickness 0.15)) (justify left bottom))
    )
    (fp_rect (start -0.93 -0.47) (end 0.93 0.47) (layer "F.CrtYd") (width 0.05) (fill none))
    (fp_rect (start -0.5 -0.25) (end 0.5 0.25) (layer "F.Fab") (width 0.15) (fill none))
    (pad "1" smd roundrect (at -0.485 0) (size 0.59 0.64) (layers "F.Cu" "F.Paste" "F.Mask") (roundrect_rratio 0.25)
      (net 404 "Net-(R117-Pad1)") (pintype "passive"))
    (pad "2" smd roundrect (at 0.485 0) (size 0.59 0.64) (layers "F.Cu" "F.Paste" "F.Mask") (roundrect_rratio 0.25)
      (net 1 "GND") (pintype "passive"))
  )
)
